# SCM (Grand Teton) — schematic netlist excerpt (pin names and nets, part order shuffled) for the footprints in the layout excerpt that follows; sources: Cadence DE-HDL packaged netlist, KiCad conversion of 12092022_DA0F0TMDCD0_F0T_Management_Board_D_brd_V3_OCP.brd

H4  HOLE  EMPTY  pkg TH  page 57 : \1\ = GND
R48  Q_RES  33.2 1% EMPTY  pkg 0402LF  page 21 : A = EMMC_CMD_R ; B = BMC_EMMC_CMD
R29  Q_RES  33.2 1% CHIP  pkg 0402LF  page 23 : A = V_BMC_LS_DDC_SDA ; B = V_BMC_LS_DDC_SDA_R

(kicad_pcb
	(version 20260206)
	(generator "pcbnew")
	(generator_version "10.0")
	(general
		(thickness 1.6)
		(legacy_teardrops no)
	)
	(paper "A4")
	(title_block
		(title "12092022_DA0F0TMDCD0_F0T_Management_Board_D_brd_V3_OCP.brd")
		(comment 1 "Grand Teton / footprints 246-248 of 1440")
	)
	(layers
		(0 "F.Cu" signal "TOP")
		(4 "In1.Cu" signal "GND")
		(6 "In2.Cu" signal "IN1")
		(8 "In3.Cu" signal "GND1")
		(10 "In4.Cu" signal "IN2")
		(12 "In5.Cu" signal "VCC")
		(14 "In6.Cu" signal "VCC1")
		(16 "In7.Cu" signal "IN3")
		(18 "In8.Cu" signal "GND2")
		(20 "In9.Cu" signal "IN4")
		(22 "In10.Cu" signal "GND3")
		(2 "B.Cu" signal "BOTTOM")
		(9 "F.Adhes" user "F.Adhesive")
		(11 "B.Adhes" user "B.Adhesive")
		(13 "F.Paste" user "Package Geometry/Pastemask Top")
		(15 "B.Paste" user "Package Geometry/Pastemask Bottom")
		(5 "F.SilkS" user "Ref Des/Silkscreen Top")
		(7 "B.SilkS" user "Ref Des/Silkscreen Bottom")
		(1 "F.Mask" user "Board Geometry/Soldermask Top")
		(3 "B.Mask" user "Board Geometry/Soldermask Bottom")
		(17 "Dwgs.User" user "User.Drawings")
		(19 "Cmts.User" user "User.Comments")
		(21 "Eco1.User" user "User.Eco1")
		(23 "Eco2.User" user "User.Eco2")
		(25 "Edge.Cuts" user "Board Geometry/Outline")
		(27 "Margin" user)
		(31 "F.CrtYd" user "Package Geometry/Place Bound Top")
		(29 "B.CrtYd" user "Package Geometry/Place Bound Bottom")
		(35 "F.Fab" user "Ref Des/Assembly Top")
		(33 "B.Fab" user "Ref Des/Assembly Bottom")
	)
	(footprint ""
		(layer "F.Cu")
		(at 26.1112 -21.971 90)
		(property "Reference" "R29"
			(at 0 0 90)
			(layer "F.SilkS")
			(hide yes)
			(effects
				(font
					(size 1.27 1.27)
				)
			)
		)
		(property "Value" ""
			(at 0 0 90)
			(layer "F.Fab")
			(effects
				(font
					(size 1.27 1.27)
				)
			)
		)
		(duplicate_pad_numbers_are_jumpers no)
		(fp_line
			(start 0.7874 -0.4064)
			(end 0.7874 0.4064)
			(stroke
				(width 0.1524)
				(type default)
			)
			(layer "F.SilkS")
		)
		(fp_line
			(start -0.7874 -0.4064)
			(end 0.7874 -0.4064)
			(stroke
				(width 0.1524)
				(type default)
			)
			(layer "F.SilkS")
		)
		(fp_line
			(start 0.7874 0.4064)
			(end -0.7874 0.4064)
			(stroke
				(width 0.1524)
				(type default)
			)
			(layer "F.SilkS")
		)
		(fp_line
			(start -0.7874 0.4064)
			(end -0.7874 -0.4064)
			(stroke
				(width 0.1524)
				(type default)
			)
			(layer "F.SilkS")
		)
		(fp_line
			(start -0.12065 -0.305054)
			(end -0.12065 -0.2794)
			(stroke
				(width 0.1)
				(type default)
			)
			(layer "F.Fab")
		)
		(fp_line
			(start -0.67945 -0.305054)
			(end -0.12065 -0.305054)
			(stroke
				(width 0.1)
				(type default)
			)
			(layer "F.Fab")
		)
		(fp_line
			(start 0.67945 -0.3048)
			(end 0.67945 0.3048)
			(stroke
				(width 0.1)
				(type default)
			)
			(layer "F.Fab")
		)
		(fp_line
			(start 0.12065 -0.3048)
			(end 0.67945 -0.3048)
			(stroke
				(width 0.1)
				(type default)
			)
			(layer "F.Fab")
		)
		(fp_line
			(start 0.12065 -0.2794)
			(end 0.12065 -0.3048)
			(stroke
				(width 0.1)
				(type default)
			)
			(layer "F.Fab")
		)
		(fp_line
			(start -0.12065 -0.2794)
			(end 0.12065 -0.2794)
			(stroke
				(width 0.1)
				(type default)
			)
			(layer "F.Fab")
		)
		(fp_line
			(start 0.120396 0.2794)
			(end -0.12065 0.2794)
			(stroke
				(width 0.1)
				(type default)
			)
			(layer "F.Fab")
		)
		(fp_line
			(start -0.12065 0.2794)
			(end -0.12065 0.3048)
			(stroke
				(width 0.1)
				(type default)
			)
			(layer "F.Fab")
		)
		(fp_line
			(start 0.67945 0.3048)
			(end 0.120396 0.3048)
			(stroke
				(width 0.1)
				(type default)
			)
			(layer "F.Fab")
		)
		(fp_line
			(start 0.120396 0.3048)
			(end 0.120396 0.2794)
			(stroke
				(width 0.1)
				(type default)
			)
			(layer "F.Fab")
		)
		(fp_line
			(start -0.12065 0.3048)
			(end -0.67945 0.3048)
			(stroke
				(width 0.1)
				(type default)
			)
			(layer "F.Fab")
		)
		(fp_line
			(start -0.67945 0.3048)
			(end -0.67945 -0.305054)
			(stroke
				(width 0.1)
				(type default)
			)
			(layer "F.Fab")
		)
		(pad "1" smd circle
			(at -0.40005 0 90)
			(size 0 0)
			(layers "F.Cu" "F.Mask" "F.Paste")
			(net "V_BMC_LS_DDC_SDA")
		)
		(pad "2" smd circle
			(at 0.40005 0 90)
			(size 0 0)
			(layers "F.Cu" "F.Mask" "F.Paste")
			(net "V_BMC_LS_DDC_SDA_R")
		)
	)
	(footprint ""
		(layer "F.Cu")
		(at 59.99988 -107.700064)
		(property "Reference" "H4"
			(at -2.8702 -3.241548 0)
			(unlocked yes)
			(layer "F.SilkS")
			(effects
				(font
					(size 0.7874 0.5842)
					(thickness 0.1524)
				)
				(justify left)
			)
		)
		(property "Value" ""
			(at 0 0 0)
			(layer "F.Fab")
			(effects
				(font
					(size 1.27 1.27)
				)
			)
		)
		(duplicate_pad_numbers_are_jumpers no)
		(pad "1" thru_hole circle
			(at 0 0)
			(size 6.0198 6.0198)
			(drill 3.4036)
			(layers "*.Cu" "*.Mask")
			(remove_unused_layers no)
			(net "GND")
			(clearance -1.0541)
		)
	)
	(footprint ""
		(layer "F.Cu")
		(at 29.951172 -83.816952 90)
		(property "Reference" "R48"
			(at 0 0 90)
			(layer "F.SilkS")
			(hide yes)
			(effects
				(font
					(size 1.27 1.27)
				)
			)
		)
		(property "Value" ""
			(at 0 0 90)
			(layer "F.Fab")
			(effects
				(font
					(size 1.27 1.27)
				)
			)
		)
		(duplicate_pad_numbers_are_jumpers no)
		(fp_line
			(start 0.7874 -0.4064)
			(end 0.7874 0.4064)
			(stroke
				(width 0.1524)
				(type default)
			)
			(layer "F.SilkS")
		)
		(fp_line
			(start -0.7874 -0.4064)
			(end 0.7874 -0.4064)
			(stroke
				(width 0.1524)
				(type default)
			)
			(layer "F.SilkS")
		)
		(fp_line
			(start 0.7874 0.4064)
			(end -0.7874 0.4064)
			(stroke
				(width 0.1524)
				(type default)
			)
			(layer "F.SilkS")
		)
		(fp_line
			(start -0.7874 0.4064)
			(end -0.7874 -0.4064)
			(stroke
				(width 0.1524)
				(type default)
			)
			(layer "F.SilkS")
		)
		(fp_line
			(start -0.12065 -0.305054)
			(end -0.12065 -0.2794)
			(stroke
				(width 0.1)
				(type default)
			)
			(layer "F.Fab")
		)
		(fp_line
			(start -0.67945 -0.305054)
			(end -0.12065 -0.305054)
			(stroke
				(width 0.1)
				(type default)
			)
			(layer "F.Fab")
		)
		(fp_line
			(start 0.67945 -0.3048)
			(end 0.67945 0.3048)
			(stroke
				(width 0.1)
				(type default)
			)
			(layer "F.Fab")
		)
		(fp_line
			(start 0.12065 -0.3048)
			(end 0.67945 -0.3048)
			(stroke
				(width 0.1)
				(type default)
			)
			(layer "F.Fab")
		)
		(fp_line
			(start 0.12065 -0.2794)
			(end 0.12065 -0.3048)
			(stroke
				(width 0.1)
				(type default)
			)
			(layer "F.Fab")
		)
		(fp_line
			(start -0.12065 -0.2794)
			(end 0.12065 -0.2794)
			(stroke
				(width 0.1)
				(type default)
			)
			(layer "F.Fab")
		)
		(fp_line
			(start 0.120396 0.2794)
			(end -0.12065 0.2794)
			(stroke
				(width 0.1)
				(type default)
			)
			(layer "F.Fab")
		)
		(fp_line
			(start -0.12065 0.2794)
			(end -0.12065 0.3048)
			(stroke
				(width 0.1)
				(type default)
			)
			(layer "F.Fab")
		)
		(fp_line
			(start 0.67945 0.3048)
			(end 0.120396 0.3048)
			(stroke
				(width 0.1)
				(type default)
			)
			(layer "F.Fab")
		)
		(fp_line
			(start 0.120396 0.3048)
			(end 0.120396 0.2794)
			(stroke
				(width 0.1)
				(type default)
			)
			(layer "F.Fab")
		)
		(fp_line
			(start -0.12065 0.3048)
			(end -0.67945 0.3048)
			(stroke
				(width 0.1)
				(type default)
			)
			(layer "F.Fab")
		)
		(fp_line
			(start -0.67945 0.3048)
			(end -0.67945 -0.305054)
			(stroke
				(width 0.1)
				(type default)
			)
			(layer "F.Fab")
		)
		(pad "1" smd circle
			(at -0.40005 0 90)
			(size 0 0)
			(layers "F.Cu" "F.Mask" "F.Paste")
			(net "EMMC_CMD_R")
		)
		(pad "2" smd circle
			(at 0.40005 0 90)
			(size 0 0)
			(layers "F.Cu" "F.Mask" "F.Paste")
			(net "BMC_EMMC_CMD")
		)
	)
)
